;LEADER: 12 
;HEADER: 
;CODE  : ASCII 
;FILE  : 9332_F0TG_MB_C_V02_0417_0820-bd-1-13.drl for backdrilling ... from layer TOP to layer GND5
;DESIGN: 9332_F0TG_MB_C_V02_0417_0820.brd
;MUST-NOT-CUT-LAYER = IN5,  MAX_DRILL_DEPTH = 72.65 MILS,  MFG_STUB_LENGTH = 0.00 MILS
;   BackdrillSize 1. = 17.000000 Tolerance = +0.000000/-0.000000 NON_PLATED MILS Quantity = 12
%
G90
X1436263Y-0031711
X1245840Y-0031711
X1436263Y-0028311
X1245840Y-0028311
X0725925Y-0015571
X0390841Y-0015571
X0725925Y-0012171
X0390841Y-0012171
X0687697Y0960966
X1663839Y0960965
X0209768Y0960966
X1185910Y0960965
M30
